# BASEBOARD_FAB2 (Tioga Pass) — schematic netlist excerpt (pin names and nets, part order shuffled) for the footprints in the layout excerpt that follows; sources: Cadence DE-HDL packaged netlist, KiCad conversion of Wiwynn_Tioga_Pass_MB.brd

T1P4  TPAD-DIFF-4P-GP  pkg DISCRET-GB3  page 256
  \1\  = L10_85OHM_6INCH_DP
  \2\  = L10_85OHM_6INCH_DN
  GND1  = GND
  GND2  = GND

C7F15  CAP_A  0.1UF 16V 10% X7R  pkg 0402V  page 215 : A = VR_PVDDQ_ABC_VD12 ; B = GND

(kicad_pcb
	(version 20260206)
	(generator "pcbnew")
	(generator_version "10.0")
	(general
		(thickness 1.6)
		(legacy_teardrops no)
	)
	(paper "A4")
	(title_block
		(title "Wiwynn_Tioga_Pass_MB.brd")
		(comment 1 "Tioga Pass / footprints 34-35 of 4770")
	)
	(layers
		(0 "F.Cu" signal "TOP")
		(4 "In1.Cu" signal "L2GND")
		(6 "In2.Cu" signal "L3")
		(8 "In3.Cu" signal "L4GND")
		(10 "In4.Cu" signal "L5")
		(12 "In5.Cu" signal "L6GND")
		(14 "In6.Cu" signal "L7VCC")
		(16 "In7.Cu" signal "L8VCC")
		(18 "In8.Cu" signal "L9GND")
		(20 "In9.Cu" signal "L10")
		(22 "In10.Cu" signal "L11GND")
		(24 "In11.Cu" signal "L12")
		(26 "In12.Cu" signal "L13GND")
		(2 "B.Cu" signal "BOTTOM")
		(9 "F.Adhes" user "F.Adhesive")
		(11 "B.Adhes" user "B.Adhesive")
		(13 "F.Paste" user "Package Geometry/Pastemask Top")
		(15 "B.Paste" user "Package Geometry/Pastemask Bottom")
		(5 "F.SilkS" user "Ref Des/Silkscreen Top")
		(7 "B.SilkS" user "Ref Des/Silkscreen Bottom")
		(1 "F.Mask" user "Board Geometry/Soldermask Top")
		(3 "B.Mask" user "Board Geometry/Soldermask Bottom")
		(17 "Dwgs.User" user "User.Drawings")
		(19 "Cmts.User" user "User.Comments")
		(21 "Eco1.User" user "User.Eco1")
		(23 "Eco2.User" user "User.Eco2")
		(25 "Edge.Cuts" user "Board Geometry/Outline")
		(27 "Margin" user)
		(31 "F.CrtYd" user "Package Geometry/Place Bound Top")
		(29 "B.CrtYd" user "Package Geometry/Place Bound Bottom")
		(35 "F.Fab" user "Ref Des/Assembly Top")
		(33 "B.Fab" user "Ref Des/Assembly Bottom")
	)
	(footprint ""
		(layer "F.Cu")
		(at 346.9894 -19.304 180)
		(property "Reference" "C7F15"
			(at 0 0 180)
			(layer "F.SilkS")
			(hide yes)
			(effects
				(font
					(size 1.27 1.27)
				)
			)
		)
		(property "Value" ""
			(at 0 0 180)
			(layer "F.Fab")
			(effects
				(font
					(size 1.27 1.27)
				)
			)
		)
		(duplicate_pad_numbers_are_jumpers no)
		(fp_rect
			(start 0.3048 -0.1016)
			(end -0.3048 0.9906)
			(stroke
				(width 0)
				(type default)
			)
			(fill no)
			(layer "F.CrtYd")
		)
		(fp_line
			(start 0.3048 0.9906)
			(end 0.3048 -0.1016)
			(stroke
				(width 0.1)
				(type default)
			)
			(layer "F.Fab")
		)
		(fp_line
			(start 0.3048 -0.1016)
			(end -0.3048 -0.1016)
			(stroke
				(width 0.1)
				(type default)
			)
			(layer "F.Fab")
		)
		(fp_line
			(start -0.3048 0.9906)
			(end 0.3048 0.9906)
			(stroke
				(width 0.1)
				(type default)
			)
			(layer "F.Fab")
		)
		(fp_line
			(start -0.3048 -0.1016)
			(end -0.3048 0.9906)
			(stroke
				(width 0.1)
				(type default)
			)
			(layer "F.Fab")
		)
		(pad "1" smd rect
			(at 0 0 180)
			(size 0.508 0.508)
			(layers "F.Cu" "F.Mask" "F.Paste")
			(net "VR_PVDDQ_ABC_VD12")
		)
		(pad "2" smd rect
			(at 0 0.889 180)
			(size 0.508 0.508)
			(layers "F.Cu" "F.Mask" "F.Paste")
			(net "GND")
		)
		(zone
			(layer "F.Cu")
			(hatch none 0.5)
			(connect_pads
				(clearance 0)
			)
			(min_thickness 0.25)
			(keepout
				(tracks allowed)
				(vias not_allowed)
				(pads allowed)
				(copperpour not_allowed)
				(footprints allowed)
			)
			(placement
				(enabled no)
				(sheetname "")
			)
			(fill
				(thermal_gap 0.5)
				(thermal_bridge_width 0.5)
				(island_removal_mode 0)
			)
			(polygon
				(pts
					(xy 346.7354 -19.558) (xy 347.2434 -19.558) (xy 347.2434 -19.939) (xy 346.7354 -19.939)
				)
			)
		)
		(zone
			(layer "F.Cu")
			(hatch none 0.5)
			(connect_pads
				(clearance 0)
			)
			(min_thickness 0.25)
			(keepout
				(tracks not_allowed)
				(vias allowed)
				(pads allowed)
				(copperpour not_allowed)
				(footprints allowed)
			)
			(placement
				(enabled no)
				(sheetname "")
			)
			(fill
				(thermal_gap 0.5)
				(thermal_bridge_width 0.5)
				(island_removal_mode 0)
			)
			(polygon
				(pts
					(xy 346.7354 -19.558) (xy 347.2434 -19.558) (xy 347.2434 -19.939) (xy 346.7354 -19.939)
				)
			)
		)
	)
	(footprint ""
		(layer "F.Cu")
		(at 216.911936 11.952478 -90)
		(property "Reference" "T1P4"
			(at 0 0 270)
			(layer "F.SilkS")
			(hide yes)
			(effects
				(font
					(size 1.27 1.27)
				)
			)
		)
		(property "Value" "*"
			(at -3.302 1.12395 270)
			(unlocked yes)
			(layer "F.Fab")
			(hide yes)
			(effects
				(font
					(size 0.889 0.889)
					(thickness 0.1524)
				)
			)
		)
		(property "Device Type" "TPAD-DIFF-4P-GP_DISCRET-GB3-TPA"
			(at -3.302 -0.40005 270)
			(unlocked yes)
			(layer "F.Fab")
			(hide yes)
			(effects
				(font
					(size 0.889 0.889)
					(thickness 0.1524)
				)
			)
		)
		(duplicate_pad_numbers_are_jumpers no)
		(fp_line
			(start -2.286 2.286)
			(end 2.286 2.286)
			(stroke
				(width 0.1524)
				(type default)
			)
			(layer "F.SilkS")
		)
		(fp_line
			(start 2.286 2.286)
			(end 2.286 -2.286)
			(stroke
				(width 0.1524)
				(type default)
			)
			(layer "F.SilkS")
		)
		(fp_line
			(start -2.286 -2.286)
			(end -2.286 2.286)
			(stroke
				(width 0.1524)
				(type default)
			)
			(layer "F.SilkS")
		)
		(fp_line
			(start 2.286 -2.286)
			(end -2.286 -2.286)
			(stroke
				(width 0.1524)
				(type default)
			)
			(layer "F.SilkS")
		)
		(fp_line
			(start -2.413 -2.413)
			(end -2.413 -1.143)
			(stroke
				(width 0.4064)
				(type default)
			)
			(layer "F.SilkS")
		)
		(fp_line
			(start -1.143 -2.413)
			(end -2.413 -2.413)
			(stroke
				(width 0.4064)
				(type default)
			)
			(layer "F.SilkS")
		)
		(fp_rect
			(start -2.54 2.54)
			(end 2.54 -2.54)
			(stroke
				(width 0)
				(type default)
			)
			(fill no)
			(layer "F.CrtYd")
		)
		(fp_rect
			(start -2.54 2.54)
			(end 2.54 -2.54)
			(stroke
				(width 0)
				(type default)
			)
			(fill no)
			(layer "F.Fab")
		)
		(pad "1" thru_hole circle
			(at -1.27 -1.27 270)
			(size 1.524 1.524)
			(drill 0.9144)
			(layers "*.Cu" "*.Mask")
			(remove_unused_layers no)
			(net "L10_85OHM_6INCH_DP")
			(clearance -0.0508)
			(thermal_gap 0.127)
			(padstack
				(mode front_inner_back)
				(layer "Inner"
					(shape circle)
					(size 1.1684 1.1684)
					(clearance 0.127)
				)
				(layer "B.Cu"
					(shape circle)
					(size 1.524 1.524)
					(clearance -0.0508)
				)
			)
		)
		(pad "2" thru_hole circle
			(at 1.27 -1.27 270)
			(size 1.524 1.524)
			(drill 0.9144)
			(layers "*.Cu" "*.Mask")
			(remove_unused_layers no)
			(net "L10_85OHM_6INCH_DN")
			(clearance -0.0508)
			(thermal_gap 0.127)
			(padstack
				(mode front_inner_back)
				(layer "Inner"
					(shape circle)
					(size 1.1684 1.1684)
					(clearance 0.127)
				)
				(layer "B.Cu"
					(shape circle)
					(size 1.524 1.524)
					(clearance -0.0508)
				)
			)
		)
		(pad "GND1" thru_hole rect
			(at -1.27 1.27 270)
			(size 1.524 1.524)
			(drill 0.9144)
			(layers "*.Cu" "*.Mask")
			(remove_unused_layers no)
			(net "GND")
			(clearance -0.0508)
			(thermal_gap 0.127)
			(padstack
				(mode front_inner_back)
				(layer "Inner"
					(shape circle)
					(size 1.1684 1.1684)
					(clearance 0.127)
				)
				(layer "B.Cu"
					(shape rect)
					(size 1.524 1.524)
					(clearance -0.0508)
				)
			)
		)
		(pad "GND2" thru_hole rect
			(at 1.27 1.27 270)
			(size 1.524 1.524)
			(drill 0.9144)
			(layers "*.Cu" "*.Mask")
			(remove_unused_layers no)
			(net "GND")
			(clearance -0.0508)
			(thermal_gap 0.127)
			(padstack
				(mode front_inner_back)
				(layer "Inner"
					(shape circle)
					(size 1.1684 1.1684)
					(clearance 0.127)
				)
				(layer "B.Cu"
					(shape rect)
					(size 1.524 1.524)
					(clearance -0.0508)
				)
			)
		)
	)
)
